# SCM (Grand Teton) — schematic netlist excerpt (pin names and nets, part order shuffled) for the footprints in the layout excerpt that follows; sources: Cadence DE-HDL packaged netlist, KiCad conversion of 12092022_DA0F0TMDCD0_F0T_Management_Board_D_brd_V3_OCP.brd

U17  MX25L51245GMI10G  MX25L51245GMI-10G EMPTY  pkg SOP16_1-27_10-3X7-52  page 45
  NC_SIO3  = SPI_PCH_IO3_FLASH_R1
  VCC  = P3V3_AUX
  \reset#\  = RST_SPI_PCH_FLASH_R1_N
  NC1  = TP_J40_4
  DNU1  = TP_J40_5
  DNU2  = TP_J40_6
  \cs#\  = SPI_PCH_CS0_FLASH_R1_N
  SO_SIO1  = SPI_PCH_IO1_FLASH_R1
  \wp#_sio2\  = SPI_PCH_IO2_FLASH_R1
  GND  = GND
  DNU3  = TP_J40_11
  DNU4  = TP_J40_12
  NC2  = TP_J40_13
  NC3  = TP_J40_14
  SI_SIO0  = SPI_PCH_IO0_FLASH_R1
  SCLK  = SPI_PCH_CLK_FLASH_R1

D4  Q_LED  IC  pkg SMLF  page 47 : A = LED_POSTCODE_4_R ; C = GND

(kicad_pcb
	(version 20260206)
	(generator "pcbnew")
	(generator_version "10.0")
	(general
		(thickness 1.6)
		(legacy_teardrops no)
	)
	(paper "A4")
	(title_block
		(title "12092022_DA0F0TMDCD0_F0T_Management_Board_D_brd_V3_OCP.brd")
		(comment 1 "Grand Teton / footprints 598-599 of 1440")
	)
	(layers
		(0 "F.Cu" signal "TOP")
		(4 "In1.Cu" signal "GND")
		(6 "In2.Cu" signal "IN1")
		(8 "In3.Cu" signal "GND1")
		(10 "In4.Cu" signal "IN2")
		(12 "In5.Cu" signal "VCC")
		(14 "In6.Cu" signal "VCC1")
		(16 "In7.Cu" signal "IN3")
		(18 "In8.Cu" signal "GND2")
		(20 "In9.Cu" signal "IN4")
		(22 "In10.Cu" signal "GND3")
		(2 "B.Cu" signal "BOTTOM")
		(9 "F.Adhes" user "F.Adhesive")
		(11 "B.Adhes" user "B.Adhesive")
		(13 "F.Paste" user "Package Geometry/Pastemask Top")
		(15 "B.Paste" user "Package Geometry/Pastemask Bottom")
		(5 "F.SilkS" user "Ref Des/Silkscreen Top")
		(7 "B.SilkS" user "Ref Des/Silkscreen Bottom")
		(1 "F.Mask" user "Board Geometry/Soldermask Top")
		(3 "B.Mask" user "Board Geometry/Soldermask Bottom")
		(17 "Dwgs.User" user "User.Drawings")
		(19 "Cmts.User" user "User.Comments")
		(21 "Eco1.User" user "User.Eco1")
		(23 "Eco2.User" user "User.Eco2")
		(25 "Edge.Cuts" user "Board Geometry/Outline")
		(27 "Margin" user)
		(31 "F.CrtYd" user "Package Geometry/Place Bound Top")
		(29 "B.CrtYd" user "Package Geometry/Place Bound Bottom")
		(35 "F.Fab" user "Ref Des/Assembly Top")
		(33 "B.Fab" user "Ref Des/Assembly Bottom")
	)
	(footprint ""
		(layer "F.Cu")
		(at 39.500302 -97.910142 90)
		(property "Reference" "U17"
			(at 1.861058 9.345168 90)
			(unlocked yes)
			(layer "F.SilkS")
			(effects
				(font
					(size 0.7874 0.5842)
					(thickness 0.1524)
				)
				(justify left)
			)
		)
		(property "Value" ""
			(at 0 0 90)
			(layer "F.Fab")
			(effects
				(font
					(size 1.27 1.27)
				)
			)
		)
		(duplicate_pad_numbers_are_jumpers no)
		(fp_line
			(start 3.800094 -5.249926)
			(end 3.800094 5.249926)
			(stroke
				(width 0.1524)
				(type default)
			)
			(layer "F.SilkS")
		)
		(fp_line
			(start 1.693926 -5.249926)
			(end 3.800094 -5.249926)
			(stroke
				(width 0.1524)
				(type default)
			)
			(layer "F.SilkS")
		)
		(fp_line
			(start -1.693926 -5.249926)
			(end 0 -4.064)
			(stroke
				(width 0.1524)
				(type default)
			)
			(layer "F.SilkS")
		)
		(fp_line
			(start -3.800094 -5.249926)
			(end -1.693926 -5.249926)
			(stroke
				(width 0.1524)
				(type default)
			)
			(layer "F.SilkS")
		)
		(fp_line
			(start 0 -4.064)
			(end 1.693926 -5.249926)
			(stroke
				(width 0.1524)
				(type default)
			)
			(layer "F.SilkS")
		)
		(fp_line
			(start 3.800094 5.249926)
			(end -3.800094 5.249926)
			(stroke
				(width 0.1524)
				(type default)
			)
			(layer "F.SilkS")
		)
		(fp_line
			(start -3.800094 5.249926)
			(end -3.800094 -5.249926)
			(stroke
				(width 0.1524)
				(type default)
			)
			(layer "F.SilkS")
		)
		(fp_poly
			(pts
				(xy -8.128254 -4.953254) (xy -8.128254 -3.937254) (xy -7.112254 -4.445254)
			)
			(stroke
				(width 0)
				(type default)
			)
			(fill yes)
			(layer "F.SilkS")
		)
		(fp_line
			(start 3.800094 -5.249926)
			(end -3.800094 -5.249926)
			(stroke
				(width 0.1)
				(type default)
			)
			(layer "F.Fab")
		)
		(fp_line
			(start -3.800094 -5.249926)
			(end -3.800094 5.249926)
			(stroke
				(width 0.1)
				(type default)
			)
			(layer "F.Fab")
		)
		(fp_line
			(start 3.800094 5.249926)
			(end 3.800094 -5.249926)
			(stroke
				(width 0.1)
				(type default)
			)
			(layer "F.Fab")
		)
		(fp_line
			(start -3.800094 5.249926)
			(end 3.800094 5.249926)
			(stroke
				(width 0.1)
				(type default)
			)
			(layer "F.Fab")
		)
		(fp_poly
			(pts
				(xy -7.2644 -4.953) (xy -7.2644 -3.937) (xy -6.2484 -4.445)
			)
			(stroke
				(width 0)
				(type default)
			)
			(fill yes)
			(layer "F.Fab")
		)
		(pad "1" smd rect
			(at -5.150104 -4.445)
			(size 0.4318 1.7018)
			(layers "F.Cu" "F.Mask" "F.Paste")
			(net "SPI_PCH_IO3_FLASH_R1")
		)
		(pad "2" smd rect
			(at -5.150104 -3.175)
			(size 0.4318 1.7018)
			(layers "F.Cu" "F.Mask" "F.Paste")
			(net "P3V3_AUX")
		)
		(pad "3" smd rect
			(at -5.150104 -1.905)
			(size 0.4318 1.7018)
			(layers "F.Cu" "F.Mask" "F.Paste")
			(net "RST_SPI_PCH_FLASH_R1_N")
		)
		(pad "4" smd rect
			(at -5.150104 -0.635)
			(size 0.4318 1.7018)
			(layers "F.Cu" "F.Mask" "F.Paste")
			(net "TP_J40_4")
		)
		(pad "5" smd rect
			(at -5.150104 0.635)
			(size 0.4318 1.7018)
			(layers "F.Cu" "F.Mask" "F.Paste")
			(net "TP_J40_5")
		)
		(pad "6" smd rect
			(at -5.150104 1.905)
			(size 0.4318 1.7018)
			(layers "F.Cu" "F.Mask" "F.Paste")
			(net "TP_J40_6")
		)
		(pad "7" smd rect
			(at -5.150104 3.175)
			(size 0.4318 1.7018)
			(layers "F.Cu" "F.Mask" "F.Paste")
			(net "SPI_PCH_CS0_FLASH_R1_N")
		)
		(pad "8" smd rect
			(at -5.150104 4.445)
			(size 0.4318 1.7018)
			(layers "F.Cu" "F.Mask" "F.Paste")
			(net "SPI_PCH_IO1_FLASH_R1")
		)
		(pad "9" smd rect
			(at 5.150104 4.445)
			(size 0.4318 1.7018)
			(layers "F.Cu" "F.Mask" "F.Paste")
			(net "SPI_PCH_IO2_FLASH_R1")
		)
		(pad "10" smd rect
			(at 5.150104 3.175)
			(size 0.4318 1.7018)
			(layers "F.Cu" "F.Mask" "F.Paste")
			(net "GND")
		)
		(pad "11" smd rect
			(at 5.150104 1.905)
			(size 0.4318 1.7018)
			(layers "F.Cu" "F.Mask" "F.Paste")
			(net "TP_J40_11")
		)
		(pad "12" smd rect
			(at 5.150104 0.635)
			(size 0.4318 1.7018)
			(layers "F.Cu" "F.Mask" "F.Paste")
			(net "TP_J40_12")
		)
		(pad "13" smd rect
			(at 5.150104 -0.635)
			(size 0.4318 1.7018)
			(layers "F.Cu" "F.Mask" "F.Paste")
			(net "TP_J40_13")
		)
		(pad "14" smd rect
			(at 5.150104 -1.905)
			(size 0.4318 1.7018)
			(layers "F.Cu" "F.Mask" "F.Paste")
			(net "TP_J40_14")
		)
		(pad "15" smd rect
			(at 5.150104 -3.175)
			(size 0.4318 1.7018)
			(layers "F.Cu" "F.Mask" "F.Paste")
			(net "SPI_PCH_IO0_FLASH_R1")
		)
		(pad "16" smd rect
			(at 5.150104 -4.445)
			(size 0.4318 1.7018)
			(layers "F.Cu" "F.Mask" "F.Paste")
			(net "SPI_PCH_CLK_FLASH_R1")
		)
	)
	(footprint ""
		(layer "F.Cu")
		(at 78.907894 -31.764986 -90)
		(property "Reference" "D4"
			(at 4.079748 -7.092442 90)
			(unlocked yes)
			(layer "F.SilkS")
			(effects
				(font
					(size 0.7874 0.5842)
					(thickness 0.1524)
				)
				(justify left)
			)
		)
		(property "Value" ""
			(at 0 0 270)
			(layer "F.Fab")
			(effects
				(font
					(size 1.27 1.27)
				)
			)
		)
		(duplicate_pad_numbers_are_jumpers no)
		(fp_line
			(start -1.3208 0.5588)
			(end -1.3208 -0.5588)
			(stroke
				(width 0.1524)
				(type default)
			)
			(layer "F.SilkS")
		)
		(fp_line
			(start 1.3208 0.5588)
			(end -1.3208 0.5588)
			(stroke
				(width 0.1524)
				(type default)
			)
			(layer "F.SilkS")
		)
		(fp_line
			(start 1.6256 0.5588)
			(end 1.6256 -0.5588)
			(stroke
				(width 0.1524)
				(type default)
			)
			(layer "F.SilkS")
		)
		(fp_line
			(start 1.778 0.5588)
			(end 1.3208 0.5588)
			(stroke
				(width 0.1524)
				(type default)
			)
			(layer "F.SilkS")
		)
		(fp_line
			(start -1.3208 -0.5588)
			(end 1.3208 -0.5588)
			(stroke
				(width 0.1524)
				(type default)
			)
			(layer "F.SilkS")
		)
		(fp_line
			(start 1.3208 -0.5588)
			(end 1.3208 0.5588)
			(stroke
				(width 0.1524)
				(type default)
			)
			(layer "F.SilkS")
		)
		(fp_line
			(start 1.4732 -0.5588)
			(end 1.4732 0.5588)
			(stroke
				(width 0.1524)
				(type default)
			)
			(layer "F.SilkS")
		)
		(fp_line
			(start 1.778 -0.5588)
			(end 1.778 0.5588)
			(stroke
				(width 0.1524)
				(type default)
			)
			(layer "F.SilkS")
		)
		(fp_line
			(start 1.778 -0.5588)
			(end 1.3208 -0.5588)
			(stroke
				(width 0.1524)
				(type default)
			)
			(layer "F.SilkS")
		)
		(fp_line
			(start -0.8001 0.40005)
			(end -0.8001 -0.40005)
			(stroke
				(width 0.1)
				(type default)
			)
			(layer "F.Fab")
		)
		(fp_line
			(start 0.8001 0.40005)
			(end -0.8001 0.40005)
			(stroke
				(width 0.1)
				(type default)
			)
			(layer "F.Fab")
		)
		(fp_line
			(start -0.8001 -0.40005)
			(end 0.8001 -0.40005)
			(stroke
				(width 0.1)
				(type default)
			)
			(layer "F.Fab")
		)
		(fp_line
			(start 0.8001 -0.40005)
			(end 0.8001 0.40005)
			(stroke
				(width 0.1)
				(type default)
			)
			(layer "F.Fab")
		)
		(fp_text user "-"
			(at 0.642874 -1.107948 270)
			(unlocked yes)
			(layer "F.SilkS")
			(effects
				(font
					(size 1.905 1.4224)
					(thickness 0.1524)
				)
				(justify left)
			)
		)
		(fp_text user "+"
			(at -1.606804 -1.380998 270)
			(unlocked yes)
			(layer "F.SilkS")
			(effects
				(font
					(size 1.905 1.4224)
					(thickness 0.1524)
				)
				(justify left)
			)
		)
		(fp_text user "+"
			(at -2.5654 -0.22225 270)
			(unlocked yes)
			(layer "F.Fab")
			(effects
				(font
					(size 1.905 1.4224)
					(thickness 0.1524)
				)
				(justify left)
			)
		)
		(fp_text user "-"
			(at 1.6256 -0.22225 270)
			(unlocked yes)
			(layer "F.Fab")
			(effects
				(font
					(size 1.905 1.4224)
					(thickness 0.1524)
				)
				(justify left)
			)
		)
		(pad "A" smd rect
			(at -0.750062 0 270)
			(size 0.8128 0.8128)
			(layers "F.Cu" "F.Mask" "F.Paste")
			(net "LED_POSTCODE_4_R")
		)
		(pad "C" smd rect
			(at 0.750062 0 270)
			(size 0.8128 0.8128)
			(layers "F.Cu" "F.Mask" "F.Paste")
			(net "GND")
		)
	)
)
